(kicad_pcb
	(version 20241229)
	(generator "pcbnew")
	(generator_version "9.0")
	(general
		(thickness 1.6)
		(legacy_teardrops no)
	)
	(paper "A4")
	(title_block
		(title "OCuLink to PCIe adapter")
		(date "2025-06-18")
		(rev "1.0.0")
		(company "Antmicro Ltd")
		(comment 1 "www.antmicro.com")
		(comment 9 "footprints 21-25 of 159")
	)
	(layers
		(0 "F.Cu" signal)
		(4 "In1.Cu" signal)
		(6 "In2.Cu" signal)
		(2 "B.Cu" signal)
		(9 "F.Adhes" user "F.Adhesive")
		(11 "B.Adhes" user "B.Adhesive")
		(13 "F.Paste" user)
		(15 "B.Paste" user)
		(5 "F.SilkS" user "F.Silkscreen")
		(7 "B.SilkS" user "B.Silkscreen")
		(1 "F.Mask" user)
		(3 "B.Mask" user)
		(17 "Dwgs.User" user "User.Drawings")
		(19 "Cmts.User" user "User.Comments")
		(21 "Eco1.User" user "User.Eco1")
		(23 "Eco2.User" user "User.Eco2")
		(25 "Edge.Cuts" user)
		(27 "Margin" user)
		(31 "F.CrtYd" user "F.Courtyard")
		(29 "B.CrtYd" user "B.Courtyard")
		(35 "F.Fab" user)
		(33 "B.Fab" user)
	)
	(footprint "antmicro-footprints:R_0402_1005Metric"
		(layer "F.Cu")
		(at 126.332999 152.076999 -90)
		(descr "Resistor SMD 0402")
		(tags "resistor SMD 0402")
		(property "Reference" "R41"
			(at 0.923 0.332999 270)
			(layer "F.SilkS")
			(effects
				(font
					(size 0.7 0.7)
					(thickness 0.15)
				)
				(justify right top)
			)
		)
		(property "Value" "R_0R_0402"
			(at -1.011843 1.772046 90)
			(layer "F.Fab")
			(effects
				(font
					(size 0.7 0.7)
					(thickness 0.15)
				)
				(justify right top)
			)
		)
		(property "Datasheet" "https://industrial.panasonic.com/cdbs/www-data/pdf/RDA0000/AOA0000C301.pdf"
			(at 0 0 90)
			(layer "F.Fab")
			(hide yes)
			(effects
				(font
					(size 1.27 1.27)
					(thickness 0.15)
				)
			)
		)
		(property "Description" "SMD Chip Resistor, Jumper, 0 ohm, 100 mW, 0402 [1005 Metric], Thick Film, General Purpose"
			(at 0 0 90)
			(layer "F.Fab")
			(hide yes)
			(effects
				(font
					(size 1.27 1.27)
					(thickness 0.15)
				)
			)
		)
		(property "MPN" "ERJ2GE0R00X"
			(at 0 0 270)
			(unlocked yes)
			(layer "F.Fab")
			(hide yes)
			(effects
				(font
					(size 1 1)
					(thickness 0.15)
				)
			)
		)
		(property "Manufacturer" "Panasonic"
			(at 0 0 270)
			(unlocked yes)
			(layer "F.Fab")
			(hide yes)
			(effects
				(font
					(size 1 1)
					(thickness 0.15)
				)
			)
		)
		(property "License" "Apache-2.0"
			(at 0 0 270)
			(unlocked yes)
			(layer "F.Fab")
			(hide yes)
			(effects
				(font
					(size 1 1)
					(thickness 0.15)
				)
			)
		)
		(property "Author" "Antmicro"
			(at 0 0 270)
			(unlocked yes)
			(layer "F.Fab")
			(hide yes)
			(effects
				(font
					(size 1 1)
					(thickness 0.15)
				)
			)
		)
		(property "Val" "0R"
			(at 0 0 270)
			(unlocked yes)
			(layer "F.Fab")
			(hide yes)
			(effects
				(font
					(size 1 1)
					(thickness 0.15)
				)
			)
		)
		(property "Tolerance" ""
			(at 0 0 270)
			(unlocked yes)
			(layer "F.Fab")
			(hide yes)
			(effects
				(font
					(size 1 1)
					(thickness 0.15)
				)
			)
		)
		(property "Current" "1A"
			(at 0 0 270)
			(unlocked yes)
			(layer "F.Fab")
			(hide yes)
			(effects
				(font
					(size 1 1)
					(thickness 0.15)
				)
			)
		)
		(sheetname "/Power/")
		(sheetfile "power.kicad_sch")
		(attr smd dnp)
		(fp_rect
			(start -0.925 -0.47)
			(end 0.925 0.47)
			(stroke
				(width 0.05)
				(type default)
			)
			(fill no)
			(layer "F.CrtYd")
		)
		(fp_rect
			(start -0.5 -0.25)
			(end 0.5 0.25)
			(stroke
				(width 0.15)
				(type solid)
			)
			(fill no)
			(layer "F.Fab")
		)
		(fp_text user "${REFERENCE}"
			(at 0 0 90)
			(layer "F.Fab")
			(effects
				(font
					(size 0.7 0.7)
					(thickness 0.15)
				)
				(justify right top)
			)
		)
		(fp_text user "Author: Antmicro"
			(at -0.95 4.169 90)
			(layer "F.Fab")
			(effects
				(font
					(size 0.7 0.7)
					(thickness 0.15)
				)
				(justify right top)
			)
		)
		(fp_text user "License: Apache-2.0"
			(at -0.949999 5.169 90)
			(layer "F.Fab")
			(effects
				(font
					(size 0.7 0.7)
					(thickness 0.15)
				)
				(justify right top)
			)
		)
		(pad "1" smd roundrect
			(at -0.48 0 270)
			(size 0.59 0.64)
			(layers "F.Cu" "F.Mask" "F.Paste")
			(roundrect_rratio 0.25)
			(net 185 "/Power/~{PERST_CONN}")
			(pintype "passive")
		)
		(pad "2" smd roundrect
			(at 0.48 0 270)
			(size 0.59 0.64)
			(layers "F.Cu" "F.Mask" "F.Paste")
			(roundrect_rratio 0.25)
			(net 172 "/Power/~{PERST}")
			(pintype "passive")
		)
	)
	(footprint "antmicro-footprints:R_0402_1005Metric"
		(layer "F.Cu")
		(at 142.721321 50.8 -90)
		(descr "Resistor SMD 0402")
		(tags "resistor SMD 0402")
		(property "Reference" "R50"
			(at 0.95 0.321321 270)
			(layer "F.SilkS")
			(effects
				(font
					(size 0.7 0.7)
					(thickness 0.15)
				)
				(justify right top)
			)
		)
		(property "Value" "R_0R_0402"
			(at -1.011843 1.772046 90)
			(layer "F.Fab")
			(effects
				(font
					(size 0.7 0.7)
					(thickness 0.15)
				)
				(justify right top)
			)
		)
		(property "Datasheet" "https://industrial.panasonic.com/cdbs/www-data/pdf/RDA0000/AOA0000C301.pdf"
			(at 0 0 90)
			(layer "F.Fab")
			(hide yes)
			(effects
				(font
					(size 1.27 1.27)
					(thickness 0.15)
				)
			)
		)
		(property "Description" "SMD Chip Resistor, Jumper, 0 ohm, 100 mW, 0402 [1005 Metric], Thick Film, General Purpose"
			(at 0 0 90)
			(layer "F.Fab")
			(hide yes)
			(effects
				(font
					(size 1.27 1.27)
					(thickness 0.15)
				)
			)
		)
		(property "MPN" "ERJ2GE0R00X"
			(at 0 0 270)
			(unlocked yes)
			(layer "F.Fab")
			(hide yes)
			(effects
				(font
					(size 1 1)
					(thickness 0.15)
				)
			)
		)
		(property "Manufacturer" "Panasonic"
			(at 0 0 270)
			(unlocked yes)
			(layer "F.Fab")
			(hide yes)
			(effects
				(font
					(size 1 1)
					(thickness 0.15)
				)
			)
		)
		(property "License" "Apache-2.0"
			(at 0 0 270)
			(unlocked yes)
			(layer "F.Fab")
			(hide yes)
			(effects
				(font
					(size 1 1)
					(thickness 0.15)
				)
			)
		)
		(property "Author" "Antmicro"
			(at 0 0 270)
			(unlocked yes)
			(layer "F.Fab")
			(hide yes)
			(effects
				(font
					(size 1 1)
					(thickness 0.15)
				)
			)
		)
		(property "Val" "0R"
			(at 0 0 270)
			(unlocked yes)
			(layer "F.Fab")
			(hide yes)
			(effects
				(font
					(size 1 1)
					(thickness 0.15)
				)
			)
		)
		(property "Tolerance" ""
			(at 0 0 270)
			(unlocked yes)
			(layer "F.Fab")
			(hide yes)
			(effects
				(font
					(size 1 1)
					(thickness 0.15)
				)
			)
		)
		(property "Current" "1A"
			(at 0 0 270)
			(unlocked yes)
			(layer "F.Fab")
			(hide yes)
			(effects
				(font
					(size 1 1)
					(thickness 0.15)
				)
			)
		)
		(sheetname "/OCuLink/")
		(sheetfile "oculink.kicad_sch")
		(attr smd)
		(fp_rect
			(start -0.925 -0.47)
			(end 0.925 0.47)
			(stroke
				(width 0.05)
				(type default)
			)
			(fill no)
			(layer "F.CrtYd")
		)
		(fp_rect
			(start -0.5 -0.25)
			(end 0.5 0.25)
			(stroke
				(width 0.15)
				(type solid)
			)
			(fill no)
			(layer "F.Fab")
		)
		(fp_text user "License: Apache-2.0"
			(at -0.949999 5.169 90)
			(layer "F.Fab")
			(effects
				(font
					(size 0.7 0.7)
					(thickness 0.15)
				)
				(justify right top)
			)
		)
		(fp_text user "${REFERENCE}"
			(at 0 0 90)
			(layer "F.Fab")
			(effects
				(font
					(size 0.7 0.7)
					(thickness 0.15)
				)
				(justify right top)
			)
		)
		(fp_text user "Author: Antmicro"
			(at -0.95 4.169 90)
			(layer "F.Fab")
			(effects
				(font
					(size 0.7 0.7)
					(thickness 0.15)
				)
				(justify right top)
			)
		)
		(pad "1" smd roundrect
			(at -0.48 0 270)
			(size 0.59 0.64)
			(layers "F.Cu" "F.Mask" "F.Paste")
			(roundrect_rratio 0.25)
			(net 183 "/OCuLink/~{PERSTC}")
			(pintype "passive")
		)
		(pad "2" smd roundrect
			(at 0.48 0 270)
			(size 0.59 0.64)
			(layers "F.Cu" "F.Mask" "F.Paste")
			(roundrect_rratio 0.25)
			(net 185 "/Power/~{PERST_CONN}")
			(pintype "passive")
		)
	)
	(footprint "antmicro-footprints:F_1206_3216Metric"
		(layer "F.Cu")
		(at 142.999999 137.6 180)
		(property "Reference" "F2"
			(at 2.399999 0.4 180)
			(layer "F.SilkS")
			(effects
				(font
					(size 0.7 0.7)
					(thickness 0.15)
				)
				(justify right top)
			)
		)
		(property "Value" "F_7A_1206"
			(at 0 2.000001 0)
			(layer "F.Fab")
			(effects
				(font
					(size 0.7 0.7)
					(thickness 0.15)
				)
				(justify right top)
			)
		)
		(property "Datasheet" "https://us.schurter.com/pdf/english/typ_UST_1206.pdf"
			(at 0 0 0)
			(layer "F.Fab")
			(hide yes)
			(effects
				(font
					(size 1.27 1.27)
					(thickness 0.15)
				)
			)
		)
		(property "Description" "7 A 32 V AC 63 V DC Fuse Board Mount (Cartridge Style Excluded) Surface Mount 1206 (3216 Metric)"
			(at 0 0 0)
			(layer "F.Fab")
			(hide yes)
			(effects
				(font
					(size 1.27 1.27)
					(thickness 0.15)
				)
			)
		)
		(property "Manufacturer" "Schurter"
			(at 0 0 180)
			(unlocked yes)
			(layer "F.Fab")
			(hide yes)
			(effects
				(font
					(size 1 1)
					(thickness 0.15)
				)
			)
		)
		(property "MPN" "3413.0326.11"
			(at 0 0 180)
			(unlocked yes)
			(layer "F.Fab")
			(hide yes)
			(effects
				(font
					(size 1 1)
					(thickness 0.15)
				)
			)
		)
		(property "Author" "Antmicro"
			(at 0 0 180)
			(unlocked yes)
			(layer "F.Fab")
			(hide yes)
			(effects
				(font
					(size 1 1)
					(thickness 0.15)
				)
			)
		)
		(property "License" "Apache-2.0"
			(at 0 0 180)
			(unlocked yes)
			(layer "F.Fab")
			(hide yes)
			(effects
				(font
					(size 1 1)
					(thickness 0.15)
				)
			)
		)
		(sheetname "/Power/")
		(sheetfile "power.kicad_sch")
		(attr smd)
		(fp_line
			(start 0.8 0.901)
			(end -0.8 0.901)
			(stroke
				(width 0.15)
				(type solid)
			)
			(layer "F.SilkS")
		)
		(fp_line
			(start 0.8 -0.899)
			(end -0.8 -0.899)
			(stroke
				(width 0.15)
				(type solid)
			)
			(layer "F.SilkS")
		)
		(fp_rect
			(start -2.325 -1.15)
			(end 2.325 1.15)
			(stroke
				(width 0.05)
				(type default)
			)
			(fill no)
			(layer "F.CrtYd")
		)
		(fp_line
			(start 1.624 0.792)
			(end -1.677 0.792)
			(stroke
				(width 0.15)
				(type solid)
			)
			(layer "F.Fab")
		)
		(fp_line
			(start 1.624 -0.861)
			(end 1.624 0.792)
			(stroke
				(width 0.15)
				(type solid)
			)
			(layer "F.Fab")
		)
		(fp_line
			(start -1.677 0.792)
			(end -1.677 -0.861)
			(stroke
				(width 0.15)
				(type solid)
			)
			(layer "F.Fab")
		)
		(fp_line
			(start -1.677 -0.861)
			(end 1.624 -0.861)
			(stroke
				(width 0.15)
				(type solid)
			)
			(layer "F.Fab")
		)
		(fp_text user "${REFERENCE}"
			(at 0 0 0)
			(layer "F.Fab")
			(effects
				(font
					(size 0.7 0.7)
					(thickness 0.15)
				)
				(justify right top)
			)
		)
		(fp_text user "License: Apache-2.0"
			(at -1.95 5.2 0)
			(layer "F.Fab")
			(effects
				(font
					(size 0.7 0.7)
					(thickness 0.15)
				)
				(justify right top)
			)
		)
		(fp_text user "Author: Antmicro"
			(at -1.95 6.4 0)
			(layer "F.Fab")
			(effects
				(font
					(size 0.7 0.7)
					(thickness 0.15)
				)
				(justify right top)
			)
		)
		(pad "1" smd roundrect
			(at -1.5 0.001 180)
			(size 1.15 1.8)
			(layers "F.Cu" "F.Mask" "F.Paste")
			(roundrect_rratio 0.25)
			(net 169 "/Power/VCC_DC_CONN_2")
			(pintype "passive")
		)
		(pad "2" smd roundrect
			(at 1.5 0.001 180)
			(size 1.15 1.8)
			(layers "F.Cu" "F.Mask" "F.Paste")
			(roundrect_rratio 0.25)
			(net 116 "/Power/Ideal-diode-2/VIN")
			(pintype "passive")
		)
	)
	(footprint "antmicro-footprints:R_0402_1005Metric"
		(layer "F.Cu")
		(at 152.737001 57.376 -90)
		(descr "Resistor SMD 0402")
		(tags "resistor SMD 0402")
		(property "Reference" "R24"
			(at 1.074 0.361 90)
			(layer "F.SilkS")
			(effects
				(font
					(size 0.7 0.7)
					(thickness 0.15)
				)
				(justify right top)
			)
		)
		(property "Value" "R_1k_0402"
			(at -1.011843 1.772046 90)
			(layer "F.Fab")
			(effects
				(font
					(size 0.7 0.7)
					(thickness 0.15)
				)
				(justify right top)
			)
		)
		(property "Datasheet" "https://www.bourns.com/docs/product-datasheets/cr.pdf"
			(at 0 0 90)
			(layer "F.Fab")
			(hide yes)
			(effects
				(font
					(size 1.27 1.27)
					(thickness 0.15)
				)
			)
		)
		(property "Description" "SMD Chip Resistor, 1 kohm, ± 1%, 63 mW, 0402 [1005 Metric], Thick Film, General Purpose"
			(at 0 0 90)
			(layer "F.Fab")
			(hide yes)
			(effects
				(font
					(size 1.27 1.27)
					(thickness 0.15)
				)
			)
		)
		(property "MPN" "CR0402-FX-1001GLF"
			(at 0 0 270)
			(unlocked yes)
			(layer "F.Fab")
			(hide yes)
			(effects
				(font
					(size 1 1)
					(thickness 0.15)
				)
			)
		)
		(property "Manufacturer" "Bourns"
			(at 0 0 270)
			(unlocked yes)
			(layer "F.Fab")
			(hide yes)
			(effects
				(font
					(size 1 1)
					(thickness 0.15)
				)
			)
		)
		(property "License" "Apache-2.0"
			(at 0 0 270)
			(unlocked yes)
			(layer "F.Fab")
			(hide yes)
			(effects
				(font
					(size 1 1)
					(thickness 0.15)
				)
			)
		)
		(property "Author" "Antmicro"
			(at 0 0 270)
			(unlocked yes)
			(layer "F.Fab")
			(hide yes)
			(effects
				(font
					(size 1 1)
					(thickness 0.15)
				)
			)
		)
		(property "Val" "1k"
			(at 0 0 270)
			(unlocked yes)
			(layer "F.Fab")
			(hide yes)
			(effects
				(font
					(size 1 1)
					(thickness 0.15)
				)
			)
		)
		(property "Tolerance" "1%"
			(at 0 0 270)
			(unlocked yes)
			(layer "F.Fab")
			(hide yes)
			(effects
				(font
					(size 1 1)
					(thickness 0.15)
				)
			)
		)
		(sheetname "/USB-PD/")
		(sheetfile "usb-pd.kicad_sch")
		(attr smd exclude_from_bom dnp)
		(fp_rect
			(start -0.925 -0.47)
			(end 0.925 0.47)
			(stroke
				(width 0.05)
				(type default)
			)
			(fill no)
			(layer "F.CrtYd")
		)
		(fp_rect
			(start -0.5 -0.25)
			(end 0.5 0.25)
			(stroke
				(width 0.15)
				(type solid)
			)
			(fill no)
			(layer "F.Fab")
		)
		(fp_text user "Author: Antmicro"
			(at -0.95 4.169 90)
			(layer "F.Fab")
			(effects
				(font
					(size 0.7 0.7)
					(thickness 0.15)
				)
				(justify right top)
			)
		)
		(fp_text user "${REFERENCE}"
			(at 0 0 90)
			(layer "F.Fab")
			(effects
				(font
					(size 0.7 0.7)
					(thickness 0.15)
				)
				(justify right top)
			)
		)
		(fp_text user "License: Apache-2.0"
			(at -0.949999 5.169 90)
			(layer "F.Fab")
			(effects
				(font
					(size 0.7 0.7)
					(thickness 0.15)
				)
				(justify right top)
			)
		)
		(pad "1" smd roundrect
			(at -0.48 0 270)
			(size 0.59 0.64)
			(layers "F.Cu" "F.Mask" "F.Paste")
			(roundrect_rratio 0.25)
			(net 137 "/USB-PD/ISNK_FINE")
			(pintype "passive")
		)
		(pad "2" smd roundrect
			(at 0.48 0 270)
			(size 0.59 0.64)
			(layers "F.Cu" "F.Mask" "F.Paste")
			(roundrect_rratio 0.25)
			(net 117 "/USB-PD/VDDD_3V3")
			(pintype "passive")
		)
	)
	(footprint "antmicro-footprints:R_0402_1005Metric"
		(layer "F.Cu")
		(at 120.499999 131.8 180)
		(descr "Resistor SMD 0402")
		(tags "resistor SMD 0402")
		(property "Reference" "R9"
			(at 3.299999 0.4 180)
			(layer "F.SilkS")
			(effects
				(font
					(size 0.7 0.7)
					(thickness 0.15)
				)
				(justify left top)
			)
		)
		(property "Value" "R_68k_0402"
			(at -1.011843 1.772046 0)
			(layer "F.Fab")
			(effects
				(font
					(size 0.7 0.7)
					(thickness 0.15)
				)
				(justify right top)
			)
		)
		(property "Datasheet" "https://www.bourns.com/docs/product-datasheets/cr.pdf"
			(at 0 0 0)
			(layer "F.Fab")
			(hide yes)
			(effects
				(font
					(size 1.27 1.27)
					(thickness 0.15)
				)
			)
		)
		(property "Description" "SMD Chip Resistor"
			(at 0 0 0)
			(layer "F.Fab")
			(hide yes)
			(effects
				(font
					(size 1.27 1.27)
					(thickness 0.15)
				)
			)
		)
		(property "MPN" "CR0402-FX-6802GLF"
			(at 0 0 180)
			(unlocked yes)
			(layer "F.Fab")
			(hide yes)
			(effects
				(font
					(size 1 1)
					(thickness 0.15)
				)
			)
		)
		(property "Manufacturer" "Bourns"
			(at 0 0 180)
			(unlocked yes)
			(layer "F.Fab")
			(hide yes)
			(effects
				(font
					(size 1 1)
					(thickness 0.15)
				)
			)
		)
		(property "License" "Apache-2.0"
			(at 0 0 180)
			(unlocked yes)
			(layer "F.Fab")
			(hide yes)
			(effects
				(font
					(size 1 1)
					(thickness 0.15)
				)
			)
		)
		(property "Author" "Antmicro"
			(at 0 0 180)
			(unlocked yes)
			(layer "F.Fab")
			(hide yes)
			(effects
				(font
					(size 1 1)
					(thickness 0.15)
				)
			)
		)
		(property "Val" "68k"
			(at 0 0 180)
			(unlocked yes)
			(layer "F.Fab")
			(hide yes)
			(effects
				(font
					(size 1 1)
					(thickness 0.15)
				)
			)
		)
		(property "Tolerance" "1%"
			(at 0 0 180)
			(unlocked yes)
			(layer "F.Fab")
			(hide yes)
			(effects
				(font
					(size 1 1)
					(thickness 0.15)
				)
			)
		)
		(sheetname "/Power/")
		(sheetfile "power.kicad_sch")
		(attr smd)
		(fp_rect
			(start -0.925 -0.47)
			(end 0.925 0.47)
			(stroke
				(width 0.05)
				(type default)
			)
			(fill no)
			(layer "F.CrtYd")
		)
		(fp_rect
			(start -0.5 -0.25)
			(end 0.5 0.25)
			(stroke
				(width 0.15)
				(type solid)
			)
			(fill no)
			(layer "F.Fab")
		)
		(fp_text user "${REFERENCE}"
			(at 0 0 0)
			(layer "F.Fab")
			(effects
				(font
					(size 0.7 0.7)
					(thickness 0.15)
				)
				(justify right top)
			)
		)
		(fp_text user "License: Apache-2.0"
			(at -0.949999 5.169 0)
			(layer "F.Fab")
			(effects
				(font
					(size 0.7 0.7)
					(thickness 0.15)
				)
				(justify right top)
			)
		)
		(fp_text user "Author: Antmicro"
			(at -0.95 4.169 0)
			(layer "F.Fab")
			(effects
				(font
					(size 0.7 0.7)
					(thickness 0.15)
				)
				(justify right top)
			)
		)
		(pad "1" smd roundrect
			(at -0.48 0 180)
			(size 0.59 0.64)
			(layers "F.Cu" "F.Mask" "F.Paste")
			(roundrect_rratio 0.25)
			(net 108 "/Power/3V3_FB")
			(pintype "passive")
		)
		(pad "2" smd roundrect
			(at 0.48 0 180)
			(size 0.59 0.64)
			(layers "F.Cu" "F.Mask" "F.Paste")
			(roundrect_rratio 0.25)
			(net 186 "/Power/3V3_CONV")
			(pintype "passive")
		)
	)
)
